(kicad_pcb
	(version 20260206)
	(generator "pcbnew")
	(generator_version "10.0")
	(general
		(thickness 1.6)
		(legacy_teardrops no)
	)
	(paper "A4")
	(title_block
		(title "03242023_DA0F0TMBIJ0_F0T_Motherboard_J_brd_V01_OCP.brd")
		(comment 1 "Grand Teton / footprints 38-45 of 6105")
	)
	(layers
		(0 "F.Cu" signal "TOP")
		(4 "In1.Cu" signal "GND")
		(6 "In2.Cu" signal "IN1")
		(8 "In3.Cu" signal "GND1")
		(10 "In4.Cu" signal "IN2")
		(12 "In5.Cu" signal "GND2")
		(14 "In6.Cu" signal "IN3")
		(16 "In7.Cu" signal "GND3")
		(18 "In8.Cu" signal "VCC")
		(20 "In9.Cu" signal "VCC1")
		(22 "In10.Cu" signal "GND4")
		(24 "In11.Cu" signal "IN4")
		(26 "In12.Cu" signal "GND5")
		(28 "In13.Cu" signal "IN5")
		(30 "In14.Cu" signal "GND6")
		(32 "In15.Cu" signal "IN6")
		(34 "In16.Cu" signal "GND7")
		(2 "B.Cu" signal "BOTTOM")
		(9 "F.Adhes" user "F.Adhesive")
		(11 "B.Adhes" user "B.Adhesive")
		(13 "F.Paste" user "Package Geometry/Pastemask Top")
		(15 "B.Paste" user "Package Geometry/Pastemask Bottom")
		(5 "F.SilkS" user "Ref Des/Silkscreen Top")
		(7 "B.SilkS" user "Ref Des/Silkscreen Bottom")
		(1 "F.Mask" user "Board Geometry/Soldermask Top")
		(3 "B.Mask" user "Board Geometry/Soldermask Bottom")
		(17 "Dwgs.User" user "User.Drawings")
		(19 "Cmts.User" user "User.Comments")
		(21 "Eco1.User" user "User.Eco1")
		(23 "Eco2.User" user "User.Eco2")
		(25 "Edge.Cuts" user "Board Geometry/Outline")
		(27 "Margin" user)
		(31 "F.CrtYd" user "Package Geometry/Place Bound Top")
		(29 "B.CrtYd" user "Package Geometry/Place Bound Bottom")
		(35 "F.Fab" user "Ref Des/Assembly Top")
		(33 "B.Fab" user "Ref Des/Assembly Bottom")
	)
	(footprint ""
		(layer "F.Cu")
		(at 204.93736 -119.344948)
		(property "Reference" "R4175"
			(at 0 0 0)
			(layer "F.SilkS")
			(hide yes)
			(effects
				(font
					(size 1.27 1.27)
				)
			)
		)
		(property "Value" ""
			(at 0 0 0)
			(layer "F.Fab")
			(effects
				(font
					(size 1.27 1.27)
				)
			)
		)
		(duplicate_pad_numbers_are_jumpers no)
		(fp_line
			(start -0.7874 -0.4064)
			(end 0.7874 -0.4064)
			(stroke
				(width 0.1524)
				(type default)
			)
			(layer "F.SilkS")
		)
		(fp_line
			(start -0.7874 0.4064)
			(end -0.7874 -0.4064)
			(stroke
				(width 0.1524)
				(type default)
			)
			(layer "F.SilkS")
		)
		(fp_line
			(start 0.7874 -0.4064)
			(end 0.7874 0.4064)
			(stroke
				(width 0.1524)
				(type default)
			)
			(layer "F.SilkS")
		)
		(fp_line
			(start 0.7874 0.4064)
			(end -0.7874 0.4064)
			(stroke
				(width 0.1524)
				(type default)
			)
			(layer "F.SilkS")
		)
		(fp_line
			(start -0.67945 -0.305054)
			(end -0.12065 -0.305054)
			(stroke
				(width 0.1)
				(type default)
			)
			(layer "F.Fab")
		)
		(fp_line
			(start -0.67945 0.3048)
			(end -0.67945 -0.305054)
			(stroke
				(width 0.1)
				(type default)
			)
			(layer "F.Fab")
		)
		(fp_line
			(start -0.12065 -0.305054)
			(end -0.12065 -0.2794)
			(stroke
				(width 0.1)
				(type default)
			)
			(layer "F.Fab")
		)
		(fp_line
			(start -0.12065 -0.2794)
			(end 0.12065 -0.2794)
			(stroke
				(width 0.1)
				(type default)
			)
			(layer "F.Fab")
		)
		(fp_line
			(start -0.12065 0.2794)
			(end -0.12065 0.3048)
			(stroke
				(width 0.1)
				(type default)
			)
			(layer "F.Fab")
		)
		(fp_line
			(start -0.12065 0.3048)
			(end -0.67945 0.3048)
			(stroke
				(width 0.1)
				(type default)
			)
			(layer "F.Fab")
		)
		(fp_line
			(start 0.120396 0.2794)
			(end -0.12065 0.2794)
			(stroke
				(width 0.1)
				(type default)
			)
			(layer "F.Fab")
		)
		(fp_line
			(start 0.120396 0.3048)
			(end 0.120396 0.2794)
			(stroke
				(width 0.1)
				(type default)
			)
			(layer "F.Fab")
		)
		(fp_line
			(start 0.12065 -0.3048)
			(end 0.67945 -0.3048)
			(stroke
				(width 0.1)
				(type default)
			)
			(layer "F.Fab")
		)
		(fp_line
			(start 0.12065 -0.2794)
			(end 0.12065 -0.3048)
			(stroke
				(width 0.1)
				(type default)
			)
			(layer "F.Fab")
		)
		(fp_line
			(start 0.67945 -0.3048)
			(end 0.67945 0.3048)
			(stroke
				(width 0.1)
				(type default)
			)
			(layer "F.Fab")
		)
		(fp_line
			(start 0.67945 0.3048)
			(end 0.120396 0.3048)
			(stroke
				(width 0.1)
				(type default)
			)
			(layer "F.Fab")
		)
		(pad "1" smd circle
			(at -0.40005 0)
			(size 0 0)
			(layers "F.Cu" "F.Mask" "F.Paste")
			(net "RST_PCIE_PCH_DEV_PERST_N")
		)
		(pad "2" smd circle
			(at 0.40005 0)
			(size 0 0)
			(layers "F.Cu" "F.Mask" "F.Paste")
			(net "RST_PCIE_PCH_DEV_PERST_M2_R_N")
		)
	)
	(footprint ""
		(layer "F.Cu")
		(at 17.737582 -428.024036 90)
		(property "Reference" "R3443"
			(at 0 0 90)
			(layer "F.SilkS")
			(hide yes)
			(effects
				(font
					(size 1.27 1.27)
				)
			)
		)
		(property "Value" ""
			(at 0 0 90)
			(layer "F.Fab")
			(effects
				(font
					(size 1.27 1.27)
				)
			)
		)
		(duplicate_pad_numbers_are_jumpers no)
		(fp_line
			(start 0.7874 -0.4064)
			(end 0.7874 0.4064)
			(stroke
				(width 0.1524)
				(type default)
			)
			(layer "F.SilkS")
		)
		(fp_line
			(start -0.7874 -0.4064)
			(end 0.7874 -0.4064)
			(stroke
				(width 0.1524)
				(type default)
			)
			(layer "F.SilkS")
		)
		(fp_line
			(start 0.7874 0.4064)
			(end -0.7874 0.4064)
			(stroke
				(width 0.1524)
				(type default)
			)
			(layer "F.SilkS")
		)
		(fp_line
			(start -0.7874 0.4064)
			(end -0.7874 -0.4064)
			(stroke
				(width 0.1524)
				(type default)
			)
			(layer "F.SilkS")
		)
		(fp_line
			(start -0.12065 -0.305054)
			(end -0.12065 -0.2794)
			(stroke
				(width 0.1)
				(type default)
			)
			(layer "F.Fab")
		)
		(fp_line
			(start -0.67945 -0.305054)
			(end -0.12065 -0.305054)
			(stroke
				(width 0.1)
				(type default)
			)
			(layer "F.Fab")
		)
		(fp_line
			(start 0.67945 -0.3048)
			(end 0.67945 0.3048)
			(stroke
				(width 0.1)
				(type default)
			)
			(layer "F.Fab")
		)
		(fp_line
			(start 0.12065 -0.3048)
			(end 0.67945 -0.3048)
			(stroke
				(width 0.1)
				(type default)
			)
			(layer "F.Fab")
		)
		(fp_line
			(start 0.12065 -0.2794)
			(end 0.12065 -0.3048)
			(stroke
				(width 0.1)
				(type default)
			)
			(layer "F.Fab")
		)
		(fp_line
			(start -0.12065 -0.2794)
			(end 0.12065 -0.2794)
			(stroke
				(width 0.1)
				(type default)
			)
			(layer "F.Fab")
		)
		(fp_line
			(start 0.120396 0.2794)
			(end -0.12065 0.2794)
			(stroke
				(width 0.1)
				(type default)
			)
			(layer "F.Fab")
		)
		(fp_line
			(start -0.12065 0.2794)
			(end -0.12065 0.3048)
			(stroke
				(width 0.1)
				(type default)
			)
			(layer "F.Fab")
		)
		(fp_line
			(start 0.67945 0.3048)
			(end 0.120396 0.3048)
			(stroke
				(width 0.1)
				(type default)
			)
			(layer "F.Fab")
		)
		(fp_line
			(start 0.120396 0.3048)
			(end 0.120396 0.2794)
			(stroke
				(width 0.1)
				(type default)
			)
			(layer "F.Fab")
		)
		(fp_line
			(start -0.12065 0.3048)
			(end -0.67945 0.3048)
			(stroke
				(width 0.1)
				(type default)
			)
			(layer "F.Fab")
		)
		(fp_line
			(start -0.67945 0.3048)
			(end -0.67945 -0.305054)
			(stroke
				(width 0.1)
				(type default)
			)
			(layer "F.Fab")
		)
		(pad "1" smd circle
			(at -0.40005 0 90)
			(size 0 0)
			(layers "F.Cu" "F.Mask" "F.Paste")
			(net "GPU_PEX_STRAP1")
		)
		(pad "2" smd circle
			(at 0.40005 0 90)
			(size 0 0)
			(layers "F.Cu" "F.Mask" "F.Paste")
			(net "GND")
		)
	)
	(footprint ""
		(layer "F.Cu")
		(at 450.558154 -110.183422 180)
		(property "Reference" "U49"
			(at 1.041908 -2.61874 0)
			(unlocked yes)
			(layer "F.SilkS")
			(effects
				(font
					(size 0.7874 0.5842)
					(thickness 0.1524)
				)
			)
		)
		(property "Value" ""
			(at 0 0 180)
			(layer "F.Fab")
			(effects
				(font
					(size 1.27 1.27)
				)
			)
		)
		(duplicate_pad_numbers_are_jumpers no)
		(fp_line
			(start 1.949958 1.610106)
			(end -1.949958 1.610106)
			(stroke
				(width 0.1524)
				(type default)
			)
			(layer "F.SilkS")
		)
		(fp_line
			(start 1.949958 -1.560068)
			(end 1.949958 1.610106)
			(stroke
				(width 0.1524)
				(type default)
			)
			(layer "F.SilkS")
		)
		(fp_line
			(start -1.949958 1.610106)
			(end -1.949958 -1.610106)
			(stroke
				(width 0.1524)
				(type default)
			)
			(layer "F.SilkS")
		)
		(fp_line
			(start -1.949958 -1.610106)
			(end 1.949958 -1.610106)
			(stroke
				(width 0.1524)
				(type default)
			)
			(layer "F.SilkS")
		)
		(fp_line
			(start 0.750062 1.560068)
			(end -0.750062 1.560068)
			(stroke
				(width 0.1)
				(type default)
			)
			(layer "F.Fab")
		)
		(fp_line
			(start 0.750062 -1.560068)
			(end 0.750062 1.560068)
			(stroke
				(width 0.1)
				(type default)
			)
			(layer "F.Fab")
		)
		(fp_line
			(start -0.750062 1.560068)
			(end -0.750062 -1.560068)
			(stroke
				(width 0.1)
				(type default)
			)
			(layer "F.Fab")
		)
		(fp_line
			(start -0.750062 -1.560068)
			(end 0.750062 -1.560068)
			(stroke
				(width 0.1)
				(type default)
			)
			(layer "F.Fab")
		)
		(pad "D" smd rect
			(at 1.100074 0 90)
			(size 1.016 1.4224)
			(layers "F.Cu" "F.Mask" "F.Paste")
			(net "HP_LVC3_OCP_V3_1_PRSNT2")
		)
		(pad "G" smd rect
			(at -1.100074 -0.94996 90)
			(size 1.016 1.4224)
			(layers "F.Cu" "F.Mask" "F.Paste")
			(net "HP_LVC3_OCP_V3_1_PRSNT2_N")
		)
		(pad "S" smd rect
			(at -1.100074 0.94996 90)
			(size 1.016 1.4224)
			(layers "F.Cu" "F.Mask" "F.Paste")
			(net "GND")
		)
	)
	(footprint ""
		(layer "F.Cu")
		(at 80.913478 -24.333962 180)
		(property "Reference" "C2148"
			(at 0 0 180)
			(layer "F.SilkS")
			(hide yes)
			(effects
				(font
					(size 1.27 1.27)
				)
			)
		)
		(property "Value" ""
			(at 0 0 180)
			(layer "F.Fab")
			(effects
				(font
					(size 1.27 1.27)
				)
			)
		)
		(duplicate_pad_numbers_are_jumpers no)
		(fp_line
			(start 0.7874 0.4064)
			(end -0.7874 0.4064)
			(stroke
				(width 0.1524)
				(type default)
			)
			(layer "F.SilkS")
		)
		(fp_line
			(start 0.7874 -0.4064)
			(end 0.7874 0.4064)
			(stroke
				(width 0.1524)
				(type default)
			)
			(layer "F.SilkS")
		)
		(fp_line
			(start -0.7874 0.4064)
			(end -0.7874 -0.4064)
			(stroke
				(width 0.1524)
				(type default)
			)
			(layer "F.SilkS")
		)
		(fp_line
			(start -0.7874 -0.4064)
			(end 0.7874 -0.4064)
			(stroke
				(width 0.1524)
				(type default)
			)
			(layer "F.SilkS")
		)
		(fp_line
			(start 0.67945 0.3048)
			(end 0.120396 0.3048)
			(stroke
				(width 0.1)
				(type default)
			)
			(layer "F.Fab")
		)
		(fp_line
			(start 0.67945 -0.3048)
			(end 0.67945 0.3048)
			(stroke
				(width 0.1)
				(type default)
			)
			(layer "F.Fab")
		)
		(fp_line
			(start 0.12065 -0.2794)
			(end 0.12065 -0.3048)
			(stroke
				(width 0.1)
				(type default)
			)
			(layer "F.Fab")
		)
		(fp_line
			(start 0.12065 -0.3048)
			(end 0.67945 -0.3048)
			(stroke
				(width 0.1)
				(type default)
			)
			(layer "F.Fab")
		)
		(fp_line
			(start 0.120396 0.3048)
			(end 0.120396 0.2794)
			(stroke
				(width 0.1)
				(type default)
			)
			(layer "F.Fab")
		)
		(fp_line
			(start 0.120396 0.2794)
			(end -0.12065 0.2794)
			(stroke
				(width 0.1)
				(type default)
			)
			(layer "F.Fab")
		)
		(fp_line
			(start -0.12065 0.3048)
			(end -0.67945 0.3048)
			(stroke
				(width 0.1)
				(type default)
			)
			(layer "F.Fab")
		)
		(fp_line
			(start -0.12065 0.2794)
			(end -0.12065 0.3048)
			(stroke
				(width 0.1)
				(type default)
			)
			(layer "F.Fab")
		)
		(fp_line
			(start -0.12065 -0.2794)
			(end 0.12065 -0.2794)
			(stroke
				(width 0.1)
				(type default)
			)
			(layer "F.Fab")
		)
		(fp_line
			(start -0.12065 -0.305054)
			(end -0.12065 -0.2794)
			(stroke
				(width 0.1)
				(type default)
			)
			(layer "F.Fab")
		)
		(fp_line
			(start -0.67945 0.3048)
			(end -0.67945 -0.305054)
			(stroke
				(width 0.1)
				(type default)
			)
			(layer "F.Fab")
		)
		(fp_line
			(start -0.67945 -0.305054)
			(end -0.12065 -0.305054)
			(stroke
				(width 0.1)
				(type default)
			)
			(layer "F.Fab")
		)
		(pad "1" smd circle
			(at -0.40005 0 180)
			(size 0 0)
			(layers "F.Cu" "F.Mask" "F.Paste")
			(net "P12V_OCP_V3_2")
		)
		(pad "2" smd circle
			(at 0.40005 0 180)
			(size 0 0)
			(layers "F.Cu" "F.Mask" "F.Paste")
			(net "P12V_OCP_GATE_2")
		)
	)
	(footprint ""
		(layer "F.Cu")
		(at 341.52459 -70.03796 90)
		(property "Reference" "C154"
			(at 0 0 90)
			(layer "F.SilkS")
			(hide yes)
			(effects
				(font
					(size 1.27 1.27)
				)
			)
		)
		(property "Value" ""
			(at 0 0 90)
			(layer "F.Fab")
			(effects
				(font
					(size 1.27 1.27)
				)
			)
		)
		(duplicate_pad_numbers_are_jumpers no)
		(fp_line
			(start 0.299974 -0.150114)
			(end 0.299974 0.150114)
			(stroke
				(width 0.1)
				(type default)
			)
			(layer "F.Fab")
		)
		(fp_line
			(start -0.299974 -0.150114)
			(end 0.299974 -0.150114)
			(stroke
				(width 0.1)
				(type default)
			)
			(layer "F.Fab")
		)
		(fp_line
			(start 0.299974 0.150114)
			(end -0.299974 0.150114)
			(stroke
				(width 0.1)
				(type default)
			)
			(layer "F.Fab")
		)
		(fp_line
			(start -0.299974 0.150114)
			(end -0.299974 -0.150114)
			(stroke
				(width 0.1)
				(type default)
			)
			(layer "F.Fab")
		)
		(pad "1" smd rect
			(at -0.2667 0 90)
			(size 0.3048 0.381)
			(layers "F.Cu" "F.Mask" "F.Paste")
			(net "DMI_CPU0_PCH_TX_C_DP<0>")
		)
		(pad "2" smd rect
			(at 0.2667 0 90)
			(size 0.3048 0.381)
			(layers "F.Cu" "F.Mask" "F.Paste")
			(net "DMI_CPU0_PCH_TX_DP<0>")
		)
	)
	(footprint ""
		(layer "F.Cu")
		(at 92.185998 -408.517344 -90)
		(property "Reference" "C680"
			(at 0 0 270)
			(layer "F.SilkS")
			(hide yes)
			(effects
				(font
					(size 1.27 1.27)
				)
			)
		)
		(property "Value" ""
			(at 0 0 270)
			(layer "F.Fab")
			(effects
				(font
					(size 1.27 1.27)
				)
			)
		)
		(duplicate_pad_numbers_are_jumpers no)
		(fp_line
			(start -0.299974 0.150114)
			(end -0.299974 -0.150114)
			(stroke
				(width 0.1)
				(type default)
			)
			(layer "F.Fab")
		)
		(fp_line
			(start 0.299974 0.150114)
			(end -0.299974 0.150114)
			(stroke
				(width 0.1)
				(type default)
			)
			(layer "F.Fab")
		)
		(fp_line
			(start -0.299974 -0.150114)
			(end 0.299974 -0.150114)
			(stroke
				(width 0.1)
				(type default)
			)
			(layer "F.Fab")
		)
		(fp_line
			(start 0.299974 -0.150114)
			(end 0.299974 0.150114)
			(stroke
				(width 0.1)
				(type default)
			)
			(layer "F.Fab")
		)
		(pad "1" smd rect
			(at -0.2667 0 270)
			(size 0.3048 0.381)
			(layers "F.Cu" "F.Mask" "F.Paste")
			(net "P5E_CPU1_PE4_TX_C_DN<14>")
		)
		(pad "2" smd rect
			(at 0.2667 0 270)
			(size 0.3048 0.381)
			(layers "F.Cu" "F.Mask" "F.Paste")
			(net "P5E_CPU1_PE4_TX_DN<14>")
		)
	)
	(footprint ""
		(layer "F.Cu")
		(at 270.08582 -93.970348 90)
		(property "Reference" "U70"
			(at -2.84099 -0.26416 0)
			(unlocked yes)
			(layer "F.SilkS")
			(effects
				(font
					(size 0.7874 0.5842)
					(thickness 0.1524)
				)
			)
		)
		(property "Value" ""
			(at 0 0 90)
			(layer "F.Fab")
			(effects
				(font
					(size 1.27 1.27)
				)
			)
		)
		(duplicate_pad_numbers_are_jumpers no)
		(fp_line
			(start -1.949958 -1.610106)
			(end 1.949958 -1.610106)
			(stroke
				(width 0.1524)
				(type default)
			)
			(layer "F.SilkS")
		)
		(fp_line
			(start 1.949958 -1.560068)
			(end 1.949958 1.610106)
			(stroke
				(width 0.1524)
				(type default)
			)
			(layer "F.SilkS")
		)
		(fp_line
			(start 1.949958 1.610106)
			(end -1.949958 1.610106)
			(stroke
				(width 0.1524)
				(type default)
			)
			(layer "F.SilkS")
		)
		(fp_line
			(start -1.949958 1.610106)
			(end -1.949958 -1.610106)
			(stroke
				(width 0.1524)
				(type default)
			)
			(layer "F.SilkS")
		)
		(fp_line
			(start 0.750062 -1.560068)
			(end 0.750062 1.560068)
			(stroke
				(width 0.1)
				(type default)
			)
			(layer "F.Fab")
		)
		(fp_line
			(start -0.750062 -1.560068)
			(end 0.750062 -1.560068)
			(stroke
				(width 0.1)
				(type default)
			)
			(layer "F.Fab")
		)
		(fp_line
			(start 0.750062 1.560068)
			(end -0.750062 1.560068)
			(stroke
				(width 0.1)
				(type default)
			)
			(layer "F.Fab")
		)
		(fp_line
			(start -0.750062 1.560068)
			(end -0.750062 -1.560068)
			(stroke
				(width 0.1)
				(type default)
			)
			(layer "F.Fab")
		)
		(pad "D" smd rect
			(at 1.100074 0)
			(size 1.016 1.4224)
			(layers "F.Cu" "F.Mask" "F.Paste")
			(net "FM_PLD_CLKS_OE_R_N")
		)
		(pad "G" smd rect
			(at -1.100074 -0.94996)
			(size 1.016 1.4224)
			(layers "F.Cu" "F.Mask" "F.Paste")
			(net "FM_PLD_CLKS_DEV_EN")
		)
		(pad "S" smd rect
			(at -1.100074 0.94996)
			(size 1.016 1.4224)
			(layers "F.Cu" "F.Mask" "F.Paste")
			(net "GND")
		)
	)
	(footprint ""
		(layer "F.Cu")
		(at 29.332428 -98.570034 180)
		(property "Reference" "R3860"
			(at 0 0 180)
			(layer "F.SilkS")
			(hide yes)
			(effects
				(font
					(size 1.27 1.27)
				)
			)
		)
		(property "Value" ""
			(at 0 0 180)
			(layer "F.Fab")
			(effects
				(font
					(size 1.27 1.27)
				)
			)
		)
		(duplicate_pad_numbers_are_jumpers no)
		(fp_line
			(start 0.7874 0.4064)
			(end -0.7874 0.4064)
			(stroke
				(width 0.1524)
				(type default)
			)
			(layer "F.SilkS")
		)
		(fp_line
			(start 0.7874 -0.4064)
			(end 0.7874 0.4064)
			(stroke
				(width 0.1524)
				(type default)
			)
			(layer "F.SilkS")
		)
		(fp_line
			(start -0.7874 0.4064)
			(end -0.7874 -0.4064)
			(stroke
				(width 0.1524)
				(type default)
			)
			(layer "F.SilkS")
		)
		(fp_line
			(start -0.7874 -0.4064)
			(end 0.7874 -0.4064)
			(stroke
				(width 0.1524)
				(type default)
			)
			(layer "F.SilkS")
		)
		(fp_line
			(start 0.67945 0.3048)
			(end 0.120396 0.3048)
			(stroke
				(width 0.1)
				(type default)
			)
			(layer "F.Fab")
		)
		(fp_line
			(start 0.67945 -0.3048)
			(end 0.67945 0.3048)
			(stroke
				(width 0.1)
				(type default)
			)
			(layer "F.Fab")
		)
		(fp_line
			(start 0.12065 -0.2794)
			(end 0.12065 -0.3048)
			(stroke
				(width 0.1)
				(type default)
			)
			(layer "F.Fab")
		)
		(fp_line
			(start 0.12065 -0.3048)
			(end 0.67945 -0.3048)
			(stroke
				(width 0.1)
				(type default)
			)
			(layer "F.Fab")
		)
		(fp_line
			(start 0.120396 0.3048)
			(end 0.120396 0.2794)
			(stroke
				(width 0.1)
				(type default)
			)
			(layer "F.Fab")
		)
		(fp_line
			(start 0.120396 0.2794)
			(end -0.12065 0.2794)
			(stroke
				(width 0.1)
				(type default)
			)
			(layer "F.Fab")
		)
		(fp_line
			(start -0.12065 0.3048)
			(end -0.67945 0.3048)
			(stroke
				(width 0.1)
				(type default)
			)
			(layer "F.Fab")
		)
		(fp_line
			(start -0.12065 0.2794)
			(end -0.12065 0.3048)
			(stroke
				(width 0.1)
				(type default)
			)
			(layer "F.Fab")
		)
		(fp_line
			(start -0.12065 -0.2794)
			(end 0.12065 -0.2794)
			(stroke
				(width 0.1)
				(type default)
			)
			(layer "F.Fab")
		)
		(fp_line
			(start -0.12065 -0.305054)
			(end -0.12065 -0.2794)
			(stroke
				(width 0.1)
				(type default)
			)
			(layer "F.Fab")
		)
		(fp_line
			(start -0.67945 0.3048)
			(end -0.67945 -0.305054)
			(stroke
				(width 0.1)
				(type default)
			)
			(layer "F.Fab")
		)
		(fp_line
			(start -0.67945 -0.305054)
			(end -0.12065 -0.305054)
			(stroke
				(width 0.1)
				(type default)
			)
			(layer "F.Fab")
		)
		(pad "1" smd rect
			(at -0.40005 0)
			(size 0.4572 0.508)
			(layers "F.Cu" "F.Mask" "F.Paste")
			(net "P12V_OCP_V3_2_ISENSE_MPS_MAM")
		)
		(pad "2" smd rect
			(at 0.40005 0)
			(size 0.4572 0.508)
			(layers "F.Cu" "F.Mask" "F.Paste")
			(net "P12V_OCP_V3_2_ISENSE_MAM")
		)
	)
)
